(kicad_pcb
	(version 20241229)
	(generator "pcbnew")
	(generator_version "9.0")
	(general
		(thickness 1.292)
		(legacy_teardrops no)
	)
	(paper "A4")
	(title_block
		(title "LPDDR5 Testbed")
		(date "2023-12-19")
		(rev "1.0.0")
		(comment 9 "footprints 50-53 of 160")
	)
	(layers
		(0 "F.Cu" signal)
		(4 "In1.Cu" power)
		(6 "In2.Cu" power)
		(8 "In3.Cu" signal)
		(10 "In4.Cu" signal)
		(2 "B.Cu" signal)
		(9 "F.Adhes" user "F.Adhesive")
		(11 "B.Adhes" user "B.Adhesive")
		(13 "F.Paste" user)
		(15 "B.Paste" user)
		(5 "F.SilkS" user "F.Silkscreen")
		(7 "B.SilkS" user "B.Silkscreen")
		(1 "F.Mask" user)
		(3 "B.Mask" user)
		(17 "Dwgs.User" user "User.Drawings")
		(19 "Cmts.User" user "User.Comments")
		(21 "Eco1.User" user "User.Eco1")
		(23 "Eco2.User" user "User.Eco2")
		(25 "Edge.Cuts" user)
		(27 "Margin" user)
		(31 "F.CrtYd" user "F.Courtyard")
		(29 "B.CrtYd" user "B.Courtyard")
		(35 "F.Fab" user)
		(33 "B.Fab" user)
	)
	(footprint "antmicro-footprints:R_Array_4x0402_Panasonic_EXB28V"
		(layer "F.Cu")
		(at 105.375 93.8)
		(property "Reference" "R9"
			(at -1.301 -1.45 0)
			(unlocked yes)
			(layer "F.SilkS")
			(effects
				(font
					(size 0.7 0.7)
					(thickness 0.15)
				)
				(justify left bottom)
			)
		)
		(property "Value" "R_4x100R_0402_array"
			(at -1.5 2 0)
			(layer "F.Fab")
			(effects
				(font
					(size 0.7 0.7)
					(thickness 0.15)
				)
				(justify left bottom)
			)
		)
		(property "Author" "Antmicro"
			(at 0 0 0)
			(layer "F.Fab")
			(hide yes)
			(effects
				(font
					(size 1 1)
					(thickness 0.15)
				)
			)
		)
		(property "License" "Apache-2.0"
			(at 0 0 0)
			(layer "F.Fab")
			(hide yes)
			(effects
				(font
					(size 1 1)
					(thickness 0.15)
				)
			)
		)
		(property "MPN" "EXB-28V101JX"
			(at 0 0 0)
			(layer "F.Fab")
			(hide yes)
			(effects
				(font
					(size 1 1)
					(thickness 0.15)
				)
			)
		)
		(property "Manufacturer" "Panasonic"
			(at 0 0 0)
			(layer "F.Fab")
			(hide yes)
			(effects
				(font
					(size 1 1)
					(thickness 0.15)
				)
			)
		)
		(property "Val" "R_4x100R_0402"
			(at 0 0 0)
			(layer "F.Fab")
			(hide yes)
			(effects
				(font
					(size 1 1)
					(thickness 0.15)
				)
			)
		)
		(sheetname "Translators")
		(sheetfile "translators.kicad_sch")
		(attr smd)
		(fp_line
			(start -1.25 -0.5)
			(end -1.25 0.498)
			(stroke
				(width 0.15)
				(type solid)
			)
			(layer "F.SilkS")
		)
		(fp_line
			(start 1.25 0.499)
			(end 1.25 -0.499)
			(stroke
				(width 0.15)
				(type solid)
			)
			(layer "F.SilkS")
		)
		(fp_rect
			(start -1.25 -0.8)
			(end 1.25 0.8)
			(stroke
				(width 0.05)
				(type solid)
			)
			(fill no)
			(layer "F.CrtYd")
		)
		(fp_line
			(start -1 -0.5)
			(end 0.998 -0.5)
			(stroke
				(width 0.15)
				(type solid)
			)
			(layer "F.Fab")
		)
		(fp_line
			(start -1 0.498)
			(end -1 -0.5)
			(stroke
				(width 0.15)
				(type solid)
			)
			(layer "F.Fab")
		)
		(fp_line
			(start 0.998 -0.5)
			(end 0.998 0.498)
			(stroke
				(width 0.15)
				(type solid)
			)
			(layer "F.Fab")
		)
		(fp_line
			(start 0.998 0.498)
			(end -1 0.498)
			(stroke
				(width 0.15)
				(type solid)
			)
			(layer "F.Fab")
		)
		(pad "1" smd roundrect
			(at -0.8875 0.45)
			(size 0.525 0.5)
			(layers "F.Cu" "F.Mask" "F.Paste")
			(roundrect_rratio 0.25)
			(net 187 "/SODIMM/LPDDR5_IN_A.DQ8")
			(pinfunction "R1.1")
			(pintype "passive")
		)
		(pad "2" smd roundrect
			(at -0.25 0.45)
			(size 0.25 0.5)
			(layers "F.Cu" "F.Mask" "F.Paste")
			(roundrect_rratio 0.25)
			(net 185 "/SODIMM/LPDDR5_IN_A.DQ10")
			(pinfunction "R2.1")
			(pintype "passive")
		)
		(pad "3" smd roundrect
			(at 0.25 0.45)
			(size 0.25 0.5)
			(layers "F.Cu" "F.Mask" "F.Paste")
			(roundrect_rratio 0.25)
			(net 186 "/SODIMM/LPDDR5_IN_A.DQ9")
			(pinfunction "R3.1")
			(pintype "passive")
		)
		(pad "4" smd roundrect
			(at 0.8875 0.45)
			(size 0.525 0.5)
			(layers "F.Cu" "F.Mask" "F.Paste")
			(roundrect_rratio 0.25)
			(net 184 "/SODIMM/LPDDR5_IN_A.DQ11")
			(pinfunction "R4.1")
			(pintype "passive")
		)
		(pad "5" smd roundrect
			(at 0.8875 -0.45)
			(size 0.525 0.5)
			(layers "F.Cu" "F.Mask" "F.Paste")
			(roundrect_rratio 0.25)
			(net 183 "/LPDDR5/LPDDR5_A.DQ11")
			(pinfunction "R4.2")
			(pintype "passive")
		)
		(pad "6" smd roundrect
			(at 0.25 -0.45)
			(size 0.25 0.5)
			(layers "F.Cu" "F.Mask" "F.Paste")
			(roundrect_rratio 0.25)
			(net 172 "/LPDDR5/LPDDR5_A.DQ9")
			(pinfunction "R3.2")
			(pintype "passive")
		)
		(pad "7" smd roundrect
			(at -0.25 -0.45)
			(size 0.25 0.5)
			(layers "F.Cu" "F.Mask" "F.Paste")
			(roundrect_rratio 0.25)
			(net 139 "/LPDDR5/LPDDR5_A.DQ10")
			(pinfunction "R2.2")
			(pintype "passive")
		)
		(pad "8" smd roundrect
			(at -0.8875 -0.45)
			(size 0.525 0.5)
			(layers "F.Cu" "F.Mask" "F.Paste")
			(roundrect_rratio 0.25)
			(net 128 "/LPDDR5/LPDDR5_A.DQ8")
			(pinfunction "R1.2")
			(pintype "passive")
		)
	)
	(footprint "antmicro-footprints:R_0603_1608Metric"
		(layer "F.Cu")
		(at 110.6 61.075 180)
		(descr "Resistor SMD 0603")
		(tags "resistor SMD 0603")
		(property "Reference" "R44"
			(at -3.4 -0.625 0)
			(unlocked yes)
			(layer "F.SilkS")
			(effects
				(font
					(size 0.7 0.7)
					(thickness 0.15)
				)
				(justify right bottom)
			)
		)
		(property "Value" "R_0R_22.4A_0603"
			(at 0 1.6 0)
			(layer "F.Fab")
			(effects
				(font
					(size 0.7 0.7)
					(thickness 0.15)
				)
				(justify right bottom)
			)
		)
		(property "Author" "Antmicro"
			(at 221.2 122.15 0)
			(layer "F.Fab")
			(hide yes)
			(effects
				(font
					(size 1 1)
					(thickness 0.15)
				)
			)
		)
		(property "License" "Apache-2.0"
			(at 221.2 122.15 0)
			(layer "F.Fab")
			(hide yes)
			(effects
				(font
					(size 1 1)
					(thickness 0.15)
				)
			)
		)
		(property "MPN" "PMR03EZPJ000"
			(at 221.2 122.15 0)
			(layer "F.Fab")
			(hide yes)
			(effects
				(font
					(size 1 1)
					(thickness 0.15)
				)
			)
		)
		(property "Manufacturer" "ROHM Semiconductor"
			(at 221.2 122.15 0)
			(layer "F.Fab")
			(hide yes)
			(effects
				(font
					(size 1 1)
					(thickness 0.15)
				)
			)
		)
		(property "Max. Curr." "22.4A"
			(at 221.2 122.15 0)
			(layer "F.Fab")
			(hide yes)
			(effects
				(font
					(size 1 1)
					(thickness 0.15)
				)
			)
		)
		(property "Tolerance" "template_tolerance"
			(at 221.2 122.15 0)
			(layer "F.Fab")
			(hide yes)
			(effects
				(font
					(size 1 1)
					(thickness 0.15)
				)
			)
		)
		(property "Val" "0R"
			(at 221.2 122.15 0)
			(layer "F.Fab")
			(hide yes)
			(effects
				(font
					(size 1 1)
					(thickness 0.15)
				)
			)
		)
		(sheetname "Power supply")
		(sheetfile "power_supply.kicad_sch")
		(attr smd)
		(fp_line
			(start -0.3 0.3)
			(end 0.3 0.3)
			(stroke
				(width 0.15)
				(type solid)
			)
			(layer "F.SilkS")
		)
		(fp_line
			(start -0.3 -0.3)
			(end 0.3 -0.3)
			(stroke
				(width 0.15)
				(type solid)
			)
			(layer "F.SilkS")
		)
		(fp_rect
			(start -1.25 -0.7)
			(end 1.25 0.7)
			(stroke
				(width 0.05)
				(type solid)
			)
			(fill no)
			(layer "F.CrtYd")
		)
		(fp_rect
			(start -0.8 -0.4)
			(end 0.8 0.4)
			(stroke
				(width 0.15)
				(type solid)
			)
			(fill no)
			(layer "F.Fab")
		)
		(pad "1" smd roundrect
			(at -0.7 0 180)
			(size 0.6 0.8)
			(layers "F.Cu" "F.Mask" "F.Paste")
			(roundrect_rratio 0.2)
			(net 12 "+0V9")
			(pintype "passive")
		)
		(pad "2" smd roundrect
			(at 0.7 0 180)
			(size 0.6 0.8)
			(layers "F.Cu" "F.Mask" "F.Paste")
			(roundrect_rratio 0.2)
			(net 8 "/Power supply/VOUT2")
			(pintype "passive")
		)
	)
	(footprint "antmicro-footprints:R_0402_1005Metric"
		(layer "F.Cu")
		(at 164.675 64.35 180)
		(descr "Resistor SMD 0402")
		(tags "resistor SMD 0402")
		(property "Reference" "R47"
			(at 4.975 -0.65 0)
			(unlocked yes)
			(layer "F.SilkS")
			(effects
				(font
					(size 0.7 0.7)
					(thickness 0.15)
				)
				(justify right bottom)
			)
		)
		(property "Value" "R_0R_0402"
			(at -1.011843 1.772047 0)
			(layer "F.Fab")
			(effects
				(font
					(size 0.7 0.7)
					(thickness 0.15)
				)
				(justify right bottom)
			)
		)
		(property "Author" "Antmicro"
			(at 329.35 128.7 0)
			(layer "F.Fab")
			(hide yes)
			(effects
				(font
					(size 1 1)
					(thickness 0.15)
				)
			)
		)
		(property "Current" "1A"
			(at 329.35 128.7 0)
			(layer "F.Fab")
			(hide yes)
			(effects
				(font
					(size 1 1)
					(thickness 0.15)
				)
			)
		)
		(property "License" "Apache-2.0"
			(at 329.35 128.7 0)
			(layer "F.Fab")
			(hide yes)
			(effects
				(font
					(size 1 1)
					(thickness 0.15)
				)
			)
		)
		(property "MPN" "ERJ2GE0R00X"
			(at 329.35 128.7 0)
			(layer "F.Fab")
			(hide yes)
			(effects
				(font
					(size 1 1)
					(thickness 0.15)
				)
			)
		)
		(property "Manufacturer" "Panasonic"
			(at 329.35 128.7 0)
			(layer "F.Fab")
			(hide yes)
			(effects
				(font
					(size 1 1)
					(thickness 0.15)
				)
			)
		)
		(property "Tolerance" ""
			(at 329.35 128.7 0)
			(layer "F.Fab")
			(hide yes)
			(effects
				(font
					(size 1 1)
					(thickness 0.15)
				)
			)
		)
		(property "Val" "0R"
			(at 329.35 128.7 0)
			(layer "F.Fab")
			(hide yes)
			(effects
				(font
					(size 1 1)
					(thickness 0.15)
				)
			)
		)
		(sheetname "Power supply")
		(sheetfile "power_supply.kicad_sch")
		(attr smd exclude_from_pos_files exclude_from_bom dnp)
		(fp_rect
			(start -0.93 -0.47)
			(end 0.93 0.47)
			(stroke
				(width 0.05)
				(type solid)
			)
			(fill no)
			(layer "F.CrtYd")
		)
		(fp_rect
			(start -0.5 -0.25)
			(end 0.5 0.25)
			(stroke
				(width 0.15)
				(type solid)
			)
			(fill no)
			(layer "F.Fab")
		)
		(pad "1" smd roundrect
			(at -0.485 0 180)
			(size 0.59 0.64)
			(layers "F.Cu" "F.Mask" "F.Paste")
			(roundrect_rratio 0.25)
			(net 52 "Net-(POT1-Pad2)")
			(pintype "passive")
		)
		(pad "2" smd roundrect
			(at 0.485 0 180)
			(size 0.59 0.64)
			(layers "F.Cu" "F.Mask" "F.Paste")
			(roundrect_rratio 0.25)
			(net 53 "Net-(POT1-Pad3)")
			(pintype "passive")
		)
	)
	(footprint "antmicro-footprints:Trimpot_3.8mmx3.6mm_TC33X-2-103E"
		(layer "F.Cu")
		(at 164.575 62.75 -90)
		(property "Reference" "POT1"
			(at -1.15 -1.725 0)
			(unlocked yes)
			(layer "F.SilkS")
			(effects
				(font
					(size 0.7 0.7)
					(thickness 0.15)
				)
				(justify right bottom)
			)
		)
		(property "Value" "TC33X-2-203E"
			(at 0 3.3 90)
			(layer "F.Fab")
			(effects
				(font
					(size 0.7 0.7)
					(thickness 0.15)
				)
				(justify right bottom)
			)
		)
		(property "Author" "Antmicro"
			(at 101.825 227.325 0)
			(layer "F.Fab")
			(hide yes)
			(effects
				(font
					(size 1 1)
					(thickness 0.15)
				)
			)
		)
		(property "License" "Apache-2.0"
			(at 101.825 227.325 0)
			(layer "F.Fab")
			(hide yes)
			(effects
				(font
					(size 1 1)
					(thickness 0.15)
				)
			)
		)
		(property "MPN" "TC33X-2-203E"
			(at 101.825 227.325 0)
			(layer "F.Fab")
			(hide yes)
			(effects
				(font
					(size 1 1)
					(thickness 0.15)
				)
			)
		)
		(property "Manufacturer" "Bourns"
			(at 101.825 227.325 0)
			(layer "F.Fab")
			(hide yes)
			(effects
				(font
					(size 1 1)
					(thickness 0.15)
				)
			)
		)
		(sheetname "Power supply")
		(sheetfile "power_supply.kicad_sch")
		(attr smd)
		(fp_line
			(start -1.901 1.9)
			(end -1.7 1.9)
			(stroke
				(width 0.15)
				(type solid)
			)
			(layer "F.SilkS")
		)
		(fp_line
			(start 1.898 1.9)
			(end 1.699 1.9)
			(stroke
				(width 0.15)
				(type solid)
			)
			(layer "F.SilkS")
		)
		(fp_line
			(start 1.898 1.9)
			(end 1.898 1.65)
			(stroke
				(width 0.15)
				(type solid)
			)
			(layer "F.SilkS")
		)
		(fp_line
			(start -1.901 1.65)
			(end -1.901 1.9)
			(stroke
				(width 0.15)
				(type solid)
			)
			(layer "F.SilkS")
		)
		(fp_line
			(start -1.901 -2.1)
			(end -1.901 -1.85)
			(stroke
				(width 0.15)
				(type solid)
			)
			(layer "F.SilkS")
		)
		(fp_line
			(start -1.901 -2.1)
			(end -1.651 -2.1)
			(stroke
				(width 0.15)
				(type solid)
			)
			(layer "F.SilkS")
		)
		(fp_line
			(start 1.898 -2.1)
			(end 1.898 -1.85)
			(stroke
				(width 0.15)
				(type solid)
			)
			(layer "F.SilkS")
		)
		(fp_line
			(start 1.898 -2.1)
			(end 1.648 -2.1)
			(stroke
				(width 0.15)
				(type solid)
			)
			(layer "F.SilkS")
		)
		(fp_circle
			(center -1.9 2.2)
			(end -1.85 2.2)
			(stroke
				(width 0.15)
				(type solid)
			)
			(fill yes)
			(layer "F.SilkS")
		)
		(fp_rect
			(start -2.1 -2.4)
			(end 2.1 2.4)
			(stroke
				(width 0.05)
				(type solid)
			)
			(fill no)
			(layer "F.CrtYd")
		)
		(fp_line
			(start -1.801 1.799)
			(end 1.8 1.799)
			(stroke
				(width 0.15)
				(type solid)
			)
			(layer "F.Fab")
		)
		(fp_line
			(start 1.8 1.799)
			(end 1.8 -2.001)
			(stroke
				(width 0.15)
				(type solid)
			)
			(layer "F.Fab")
		)
		(fp_line
			(start -1.801 -2.001)
			(end -1.801 1.799)
			(stroke
				(width 0.15)
				(type solid)
			)
			(layer "F.Fab")
		)
		(fp_line
			(start -1.801 -2.001)
			(end 1.8 -2.001)
			(stroke
				(width 0.15)
				(type solid)
			)
			(layer "F.Fab")
		)
		(pad "1" smd rect
			(at -1 1.7 270)
			(size 1.2 1.2)
			(layers "F.Cu" "F.Mask" "F.Paste")
			(net 51 "unconnected-(POT1-Pad1)")
			(pinfunction "1")
			(pintype "passive+no_connect")
		)
		(pad "2" smd rect
			(at 0 -1.551 270)
			(size 1.6 1.5)
			(layers "F.Cu" "F.Mask" "F.Paste")
			(net 52 "Net-(POT1-Pad2)")
			(pinfunction "2")
			(pintype "passive")
		)
		(pad "3" smd rect
			(at 0.998 1.7 270)
			(size 1.2 1.2)
			(layers "F.Cu" "F.Mask" "F.Paste")
			(net 53 "Net-(POT1-Pad3)")
			(pinfunction "3")
			(pintype "passive")
		)
	)
)
